FILE_TYPE = MACRO_DRAWING;
SET COLOR_WIRE YELLOW;
SET COLOR_PROP ORANGE;
SET COLOR_DOT WHITE;
SET COLOR_ARC YELLOW;
SET COLOR_BODY GREEN;
SET COLOR_NOTE PURPLE;
SET PROP_DISPLAY VALUE;
SET PAGE_NUMBER P209;
FORCEADD QUANTA_TITLE_BLOCK_C..1
(0 0);
FORCEPROP 1 LAST CUSTOM_TXT_CDS <NAME_2>
J 0
(-3175 50);
FORCEPROP 1 LAST CUSTOM_TXT_CDS <NAME_1>
J 0
(-3175 175);
FORCEPROP 1 LAST CUSTOM_TXT_CDS <Q_NUMBER>
J 0
(-1403 103);
DISPLAY 1.212766 (-1403 103);
FORCEPROP 1 LAST CUSTOM_TXT_CDS <Q_PROJ>
J 0
(-2382 102);
DISPLAY 1.212766 (-2382 102);
FORCEPROP 1 LAST CUSTOM_TXT_CDS <Q_REV>
J 0
(-184 103);
DISPLAY 1.212766 (-184 103);
FORCEPROP 1 LAST CUSTOM_TXT_CDS <CON_LAST_MODIFIED>
J 0
(-1885 15);
DISPLAY 0.978723 (-1885 15);
FORCEPROP 1 LAST CUSTOM_TXT_CDS <CON_PAGE_NUM> OF <CON_TOTAL_PAGES>
J 0
(-446 18);
DISPLAY 0.978723 (-446 18);
FORCEPROP 1 LAST Q_TITLE eFuse - SCM
J 0
(-9366 26);
DISPLAY 2.446809 (-9366 26);
PAINT GREEN (-9366 26);
FORCEPROP 1 LAST Q_DEPT BU9
J 1
(-3763 49);
DISPLAY 1.957447 (-3763 49);
PAINT GREEN (-3763 49);
FORCEPROP 1 LAST COMMENT_BODY TRUE
J 0
(12 -13);
DISPLAY 0.978723 (12 -13);
PAINT GREEN (12 -13);
DISPLAY INVISIBLE (12 -13);
FORCEPROP 2 LAST PAGE_BORDER TRUE
J 0
(-7890 5250);
DISPLAY 0.638298 (-7890 5250);
PAINT PINK (-7890 5250);
DISPLAY INVISIBLE (-7890 5250);
FORCEPROP 1 LAST CDS_LMAN_SYM_OUTLINE -9475,6775,100,-125
J 0
(0 0);
DISPLAY 0.468085 (0 0);
PAINT GREEN (0 0);
DISPLAY INVISIBLE (0 0);
FORCEPROP 2 LAST CDS_LIB pure_quanta
J 0
(0 0);
DISPLAY INVISIBLE (0 0);
FORCEPROP 2 LAST CDS_XR_PAGE_TITLE CR-210 : @T6G_MB_LIB.T6G(SCH_1):PAGE210
J 0
(-7890 5250);
DISPLAY 0.638298 (-7890 5250);
PAINT PINK (-7890 5250);
DISPLAY INVISIBLE (-7890 5250);
FORCEPROP 2 LAST CUSTOM_TXT_CDS <XR_PAGE_TITLE>
J 0
(-7890 5250);
DISPLAY 0.638298 (-7890 5250);
PAINT PINK (-7890 5250);
DISPLAY INVISIBLE (-7890 5250);
FORCEPROP 0 LAST CDS_CON_LAST_MODIFIED Wed Mar 09 21:46:55 2022
J 0
(-1885 15);
DISPLAY INVISIBLE (-1885 15);
QUIT
